(kicad_pcb
	(version 20260206)
	(generator "pcbnew")
	(generator_version "10.0")
	(general
		(thickness 1.6)
		(legacy_teardrops no)
	)
	(paper "A4")
	(title_block
		(title "04192023_DAF0TMB3IC0_F0TG_MB_C_brd_V02_OCP.brd")
		(comment 1 "Grand Teton / footprints 609-614 of 8354")
	)
	(layers
		(0 "F.Cu" signal "TOP")
		(4 "In1.Cu" signal "GND")
		(6 "In2.Cu" signal "IN1")
		(8 "In3.Cu" signal "GND1")
		(10 "In4.Cu" signal "IN2")
		(12 "In5.Cu" signal "GND2")
		(14 "In6.Cu" signal "IN3")
		(16 "In7.Cu" signal "GND3")
		(18 "In8.Cu" signal "VCC")
		(20 "In9.Cu" signal "VCC1")
		(22 "In10.Cu" signal "GND4")
		(24 "In11.Cu" signal "IN4")
		(26 "In12.Cu" signal "GND5")
		(28 "In13.Cu" signal "IN5")
		(30 "In14.Cu" signal "GND6")
		(32 "In15.Cu" signal "IN6")
		(34 "In16.Cu" signal "GND7")
		(2 "B.Cu" signal "BOTTOM")
		(9 "F.Adhes" user "F.Adhesive")
		(11 "B.Adhes" user "B.Adhesive")
		(13 "F.Paste" user "Package Geometry/Pastemask Top")
		(15 "B.Paste" user "Package Geometry/Pastemask Bottom")
		(5 "F.SilkS" user "Ref Des/Silkscreen Top")
		(7 "B.SilkS" user "Ref Des/Silkscreen Bottom")
		(1 "F.Mask" user "Board Geometry/Soldermask Top")
		(3 "B.Mask" user "Board Geometry/Soldermask Bottom")
		(17 "Dwgs.User" user "User.Drawings")
		(19 "Cmts.User" user "User.Comments")
		(21 "Eco1.User" user "User.Eco1")
		(23 "Eco2.User" user "User.Eco2")
		(25 "Edge.Cuts" user "Board Geometry/Outline")
		(27 "Margin" user)
		(31 "F.CrtYd" user "Package Geometry/Place Bound Top")
		(29 "B.CrtYd" user "Package Geometry/Place Bound Bottom")
		(35 "F.Fab" user "Ref Des/Assembly Top")
		(33 "B.Fab" user "Ref Des/Assembly Bottom")
	)
	(footprint ""
		(layer "F.Cu")
		(at 114.629946 -54.882034 90)
		(property "Reference" "R6302"
			(at 0 0 90)
			(layer "F.SilkS")
			(hide yes)
			(effects
				(font
					(size 1.27 1.27)
				)
			)
		)
		(property "Value" ""
			(at 0 0 90)
			(layer "F.Fab")
			(effects
				(font
					(size 1.27 1.27)
				)
			)
		)
		(duplicate_pad_numbers_are_jumpers no)
		(fp_line
			(start 0.7874 -0.4064)
			(end 0.7874 0.4064)
			(stroke
				(width 0.1524)
				(type default)
			)
			(layer "F.SilkS")
		)
		(fp_line
			(start -0.7874 -0.4064)
			(end 0.7874 -0.4064)
			(stroke
				(width 0.1524)
				(type default)
			)
			(layer "F.SilkS")
		)
		(fp_line
			(start 0.7874 0.4064)
			(end -0.7874 0.4064)
			(stroke
				(width 0.1524)
				(type default)
			)
			(layer "F.SilkS")
		)
		(fp_line
			(start -0.7874 0.4064)
			(end -0.7874 -0.4064)
			(stroke
				(width 0.1524)
				(type default)
			)
			(layer "F.SilkS")
		)
		(fp_line
			(start -0.12065 -0.305054)
			(end -0.12065 -0.2794)
			(stroke
				(width 0.1)
				(type default)
			)
			(layer "F.Fab")
		)
		(fp_line
			(start -0.67945 -0.305054)
			(end -0.12065 -0.305054)
			(stroke
				(width 0.1)
				(type default)
			)
			(layer "F.Fab")
		)
		(fp_line
			(start 0.67945 -0.3048)
			(end 0.67945 0.3048)
			(stroke
				(width 0.1)
				(type default)
			)
			(layer "F.Fab")
		)
		(fp_line
			(start 0.12065 -0.3048)
			(end 0.67945 -0.3048)
			(stroke
				(width 0.1)
				(type default)
			)
			(layer "F.Fab")
		)
		(fp_line
			(start 0.12065 -0.2794)
			(end 0.12065 -0.3048)
			(stroke
				(width 0.1)
				(type default)
			)
			(layer "F.Fab")
		)
		(fp_line
			(start -0.12065 -0.2794)
			(end 0.12065 -0.2794)
			(stroke
				(width 0.1)
				(type default)
			)
			(layer "F.Fab")
		)
		(fp_line
			(start 0.120396 0.2794)
			(end -0.12065 0.2794)
			(stroke
				(width 0.1)
				(type default)
			)
			(layer "F.Fab")
		)
		(fp_line
			(start -0.12065 0.2794)
			(end -0.12065 0.3048)
			(stroke
				(width 0.1)
				(type default)
			)
			(layer "F.Fab")
		)
		(fp_line
			(start 0.67945 0.3048)
			(end 0.120396 0.3048)
			(stroke
				(width 0.1)
				(type default)
			)
			(layer "F.Fab")
		)
		(fp_line
			(start 0.120396 0.3048)
			(end 0.120396 0.2794)
			(stroke
				(width 0.1)
				(type default)
			)
			(layer "F.Fab")
		)
		(fp_line
			(start -0.12065 0.3048)
			(end -0.67945 0.3048)
			(stroke
				(width 0.1)
				(type default)
			)
			(layer "F.Fab")
		)
		(fp_line
			(start -0.67945 0.3048)
			(end -0.67945 -0.305054)
			(stroke
				(width 0.1)
				(type default)
			)
			(layer "F.Fab")
		)
		(pad "1" smd circle
			(at -0.40005 0 90)
			(size 0 0)
			(layers "F.Cu" "F.Mask" "F.Paste")
			(net "USB_HUB2_MRP_CFG_BC_EN")
		)
		(pad "2" smd circle
			(at 0.40005 0 90)
			(size 0 0)
			(layers "F.Cu" "F.Mask" "F.Paste")
			(net "GND")
		)
	)
	(footprint ""
		(layer "F.Cu")
		(at 421.174164 -176.864772)
		(property "Reference" "PR296"
			(at 0 0 0)
			(layer "F.SilkS")
			(hide yes)
			(effects
				(font
					(size 1.27 1.27)
				)
			)
		)
		(property "Value" ""
			(at 0 0 0)
			(layer "F.Fab")
			(effects
				(font
					(size 1.27 1.27)
				)
			)
		)
		(duplicate_pad_numbers_are_jumpers no)
		(fp_line
			(start -0.7874 -0.4064)
			(end 0.7874 -0.4064)
			(stroke
				(width 0.1524)
				(type default)
			)
			(layer "F.SilkS")
		)
		(fp_line
			(start -0.7874 0.4064)
			(end -0.7874 -0.4064)
			(stroke
				(width 0.1524)
				(type default)
			)
			(layer "F.SilkS")
		)
		(fp_line
			(start 0.7874 -0.4064)
			(end 0.7874 0.4064)
			(stroke
				(width 0.1524)
				(type default)
			)
			(layer "F.SilkS")
		)
		(fp_line
			(start 0.7874 0.4064)
			(end -0.7874 0.4064)
			(stroke
				(width 0.1524)
				(type default)
			)
			(layer "F.SilkS")
		)
		(fp_line
			(start -0.67945 -0.305054)
			(end -0.12065 -0.305054)
			(stroke
				(width 0.1)
				(type default)
			)
			(layer "F.Fab")
		)
		(fp_line
			(start -0.67945 0.3048)
			(end -0.67945 -0.305054)
			(stroke
				(width 0.1)
				(type default)
			)
			(layer "F.Fab")
		)
		(fp_line
			(start -0.12065 -0.305054)
			(end -0.12065 -0.2794)
			(stroke
				(width 0.1)
				(type default)
			)
			(layer "F.Fab")
		)
		(fp_line
			(start -0.12065 -0.2794)
			(end 0.12065 -0.2794)
			(stroke
				(width 0.1)
				(type default)
			)
			(layer "F.Fab")
		)
		(fp_line
			(start -0.12065 0.2794)
			(end -0.12065 0.3048)
			(stroke
				(width 0.1)
				(type default)
			)
			(layer "F.Fab")
		)
		(fp_line
			(start -0.12065 0.3048)
			(end -0.67945 0.3048)
			(stroke
				(width 0.1)
				(type default)
			)
			(layer "F.Fab")
		)
		(fp_line
			(start 0.120396 0.2794)
			(end -0.12065 0.2794)
			(stroke
				(width 0.1)
				(type default)
			)
			(layer "F.Fab")
		)
		(fp_line
			(start 0.120396 0.3048)
			(end 0.120396 0.2794)
			(stroke
				(width 0.1)
				(type default)
			)
			(layer "F.Fab")
		)
		(fp_line
			(start 0.12065 -0.3048)
			(end 0.67945 -0.3048)
			(stroke
				(width 0.1)
				(type default)
			)
			(layer "F.Fab")
		)
		(fp_line
			(start 0.12065 -0.2794)
			(end 0.12065 -0.3048)
			(stroke
				(width 0.1)
				(type default)
			)
			(layer "F.Fab")
		)
		(fp_line
			(start 0.67945 -0.3048)
			(end 0.67945 0.3048)
			(stroke
				(width 0.1)
				(type default)
			)
			(layer "F.Fab")
		)
		(fp_line
			(start 0.67945 0.3048)
			(end 0.120396 0.3048)
			(stroke
				(width 0.1)
				(type default)
			)
			(layer "F.Fab")
		)
		(pad "1" smd circle
			(at -0.40005 0)
			(size 0 0)
			(layers "F.Cu" "F.Mask" "F.Paste")
			(net "PVDDCR_SOC_P0")
		)
		(pad "2" smd circle
			(at 0.40005 0)
			(size 0 0)
			(layers "F.Cu" "F.Mask" "F.Paste")
			(net "VSENSE_PVDDCR_SOC_P0_DP")
		)
	)
	(footprint ""
		(layer "F.Cu")
		(at 299.060362 -351.927922)
		(property "Reference" "PR98"
			(at 0 0 0)
			(layer "F.SilkS")
			(hide yes)
			(effects
				(font
					(size 1.27 1.27)
				)
			)
		)
		(property "Value" ""
			(at 0 0 0)
			(layer "F.Fab")
			(effects
				(font
					(size 1.27 1.27)
				)
			)
		)
		(duplicate_pad_numbers_are_jumpers no)
		(fp_line
			(start -0.7874 -0.4064)
			(end 0.7874 -0.4064)
			(stroke
				(width 0.1524)
				(type default)
			)
			(layer "F.SilkS")
		)
		(fp_line
			(start -0.7874 0.4064)
			(end -0.7874 -0.4064)
			(stroke
				(width 0.1524)
				(type default)
			)
			(layer "F.SilkS")
		)
		(fp_line
			(start 0.7874 -0.4064)
			(end 0.7874 0.4064)
			(stroke
				(width 0.1524)
				(type default)
			)
			(layer "F.SilkS")
		)
		(fp_line
			(start 0.7874 0.4064)
			(end -0.7874 0.4064)
			(stroke
				(width 0.1524)
				(type default)
			)
			(layer "F.SilkS")
		)
		(fp_line
			(start -0.67945 -0.305054)
			(end -0.12065 -0.305054)
			(stroke
				(width 0.1)
				(type default)
			)
			(layer "F.Fab")
		)
		(fp_line
			(start -0.67945 0.3048)
			(end -0.67945 -0.305054)
			(stroke
				(width 0.1)
				(type default)
			)
			(layer "F.Fab")
		)
		(fp_line
			(start -0.12065 -0.305054)
			(end -0.12065 -0.2794)
			(stroke
				(width 0.1)
				(type default)
			)
			(layer "F.Fab")
		)
		(fp_line
			(start -0.12065 -0.2794)
			(end 0.12065 -0.2794)
			(stroke
				(width 0.1)
				(type default)
			)
			(layer "F.Fab")
		)
		(fp_line
			(start -0.12065 0.2794)
			(end -0.12065 0.3048)
			(stroke
				(width 0.1)
				(type default)
			)
			(layer "F.Fab")
		)
		(fp_line
			(start -0.12065 0.3048)
			(end -0.67945 0.3048)
			(stroke
				(width 0.1)
				(type default)
			)
			(layer "F.Fab")
		)
		(fp_line
			(start 0.120396 0.2794)
			(end -0.12065 0.2794)
			(stroke
				(width 0.1)
				(type default)
			)
			(layer "F.Fab")
		)
		(fp_line
			(start 0.120396 0.3048)
			(end 0.120396 0.2794)
			(stroke
				(width 0.1)
				(type default)
			)
			(layer "F.Fab")
		)
		(fp_line
			(start 0.12065 -0.3048)
			(end 0.67945 -0.3048)
			(stroke
				(width 0.1)
				(type default)
			)
			(layer "F.Fab")
		)
		(fp_line
			(start 0.12065 -0.2794)
			(end 0.12065 -0.3048)
			(stroke
				(width 0.1)
				(type default)
			)
			(layer "F.Fab")
		)
		(fp_line
			(start 0.67945 -0.3048)
			(end 0.67945 0.3048)
			(stroke
				(width 0.1)
				(type default)
			)
			(layer "F.Fab")
		)
		(fp_line
			(start 0.67945 0.3048)
			(end 0.120396 0.3048)
			(stroke
				(width 0.1)
				(type default)
			)
			(layer "F.Fab")
		)
		(pad "1" smd circle
			(at -0.40005 0)
			(size 0 0)
			(layers "F.Cu" "F.Mask" "F.Paste")
			(net "PVDDIO_P0_LSET1")
		)
		(pad "2" smd circle
			(at 0.40005 0)
			(size 0 0)
			(layers "F.Cu" "F.Mask" "F.Paste")
			(net "GND")
		)
	)
	(footprint ""
		(layer "F.Cu")
		(at 390.474708 -409.15082 180)
		(property "Reference" "C7001"
			(at 8.527796 1.740408 0)
			(unlocked yes)
			(layer "F.SilkS")
			(effects
				(font
					(size 0.7874 0.5842)
					(thickness 0.1524)
				)
				(justify left)
			)
		)
		(property "Value" ""
			(at 0 0 180)
			(layer "F.Fab")
			(effects
				(font
					(size 1.27 1.27)
				)
			)
		)
		(duplicate_pad_numbers_are_jumpers no)
		(fp_line
			(start 4.53898 2.15011)
			(end -4.53898 2.15011)
			(stroke
				(width 0.1524)
				(type default)
			)
			(layer "F.SilkS")
		)
		(fp_line
			(start 4.53898 -2.15011)
			(end 4.53898 2.15011)
			(stroke
				(width 0.1524)
				(type default)
			)
			(layer "F.SilkS")
		)
		(fp_line
			(start -4.53898 2.15011)
			(end -4.53898 -2.15011)
			(stroke
				(width 0.1524)
				(type default)
			)
			(layer "F.SilkS")
		)
		(fp_line
			(start -4.53898 -2.15011)
			(end 4.53898 -2.15011)
			(stroke
				(width 0.1524)
				(type default)
			)
			(layer "F.SilkS")
		)
		(fp_line
			(start -4.53898 -2.150618)
			(end -4.539742 2.152142)
			(stroke
				(width 0.1524)
				(type default)
			)
			(layer "F.SilkS")
		)
		(fp_line
			(start -4.69138 -2.150618)
			(end -4.692396 2.161032)
			(stroke
				(width 0.1524)
				(type default)
			)
			(layer "F.SilkS")
		)
		(fp_line
			(start -4.83108 2.150364)
			(end -4.447794 2.149348)
			(stroke
				(width 0.1524)
				(type default)
			)
			(layer "F.SilkS")
		)
		(fp_line
			(start -4.84378 -2.150618)
			(end -4.53898 -2.150618)
			(stroke
				(width 0.1524)
				(type default)
			)
			(layer "F.SilkS")
		)
		(fp_line
			(start -4.84378 -2.150618)
			(end -4.842256 2.163064)
			(stroke
				(width 0.1524)
				(type default)
			)
			(layer "F.SilkS")
		)
		(fp_line
			(start 3.64998 2.15011)
			(end -3.64998 2.15011)
			(stroke
				(width 0.1)
				(type default)
			)
			(layer "F.Fab")
		)
		(fp_line
			(start 3.64998 -2.15011)
			(end 3.64998 2.15011)
			(stroke
				(width 0.1)
				(type default)
			)
			(layer "F.Fab")
		)
		(fp_line
			(start -3.64998 2.15011)
			(end -3.64998 -2.15011)
			(stroke
				(width 0.1)
				(type default)
			)
			(layer "F.Fab")
		)
		(fp_line
			(start -3.64998 -2.15011)
			(end 3.64998 -2.15011)
			(stroke
				(width 0.1)
				(type default)
			)
			(layer "F.Fab")
		)
		(fp_text user "-"
			(at 4.592574 -0.165608 180)
			(unlocked yes)
			(layer "F.SilkS")
			(effects
				(font
					(size 1.905 1.4224)
					(thickness 0.1524)
				)
				(justify left)
			)
		)
		(fp_text user "+"
			(at -6.024372 -1.571498 180)
			(unlocked yes)
			(layer "F.SilkS")
			(effects
				(font
					(size 1.905 1.4224)
					(thickness 0.1524)
				)
				(justify left)
			)
		)
		(fp_text user "-"
			(at 4.313174 -0.094488 180)
			(unlocked yes)
			(layer "F.Fab")
			(effects
				(font
					(size 1.905 1.4224)
					(thickness 0.1524)
				)
				(justify left)
			)
		)
		(fp_text user "+"
			(at -6.214872 -0.337058 180)
			(unlocked yes)
			(layer "F.Fab")
			(effects
				(font
					(size 1.905 1.4224)
					(thickness 0.1524)
				)
				(justify left)
			)
		)
		(pad "1" smd rect
			(at -3.199892 0 180)
			(size 2.413 2.8194)
			(layers "F.Cu" "F.Mask" "F.Paste")
			(net "P0V9_CPU0_RT_2D")
		)
		(pad "2" smd rect
			(at 3.199892 0 180)
			(size 2.413 2.8194)
			(layers "F.Cu" "F.Mask" "F.Paste")
			(net "GND")
		)
	)
	(footprint ""
		(layer "F.Cu")
		(at 110.856014 -258.795266)
		(property "Reference" "C2503"
			(at 0 0 0)
			(layer "F.SilkS")
			(hide yes)
			(effects
				(font
					(size 1.27 1.27)
				)
			)
		)
		(property "Value" ""
			(at 0 0 0)
			(layer "F.Fab")
			(effects
				(font
					(size 1.27 1.27)
				)
			)
		)
		(duplicate_pad_numbers_are_jumpers no)
		(fp_line
			(start -0.7874 -0.4064)
			(end 0.7874 -0.4064)
			(stroke
				(width 0.1524)
				(type default)
			)
			(layer "F.SilkS")
		)
		(fp_line
			(start -0.7874 0.4064)
			(end -0.7874 -0.4064)
			(stroke
				(width 0.1524)
				(type default)
			)
			(layer "F.SilkS")
		)
		(fp_line
			(start 0.7874 -0.4064)
			(end 0.7874 0.4064)
			(stroke
				(width 0.1524)
				(type default)
			)
			(layer "F.SilkS")
		)
		(fp_line
			(start 0.7874 0.4064)
			(end -0.7874 0.4064)
			(stroke
				(width 0.1524)
				(type default)
			)
			(layer "F.SilkS")
		)
		(fp_line
			(start -0.67945 -0.305054)
			(end -0.12065 -0.305054)
			(stroke
				(width 0.1)
				(type default)
			)
			(layer "F.Fab")
		)
		(fp_line
			(start -0.67945 0.3048)
			(end -0.67945 -0.305054)
			(stroke
				(width 0.1)
				(type default)
			)
			(layer "F.Fab")
		)
		(fp_line
			(start -0.12065 -0.305054)
			(end -0.12065 -0.2794)
			(stroke
				(width 0.1)
				(type default)
			)
			(layer "F.Fab")
		)
		(fp_line
			(start -0.12065 -0.2794)
			(end 0.12065 -0.2794)
			(stroke
				(width 0.1)
				(type default)
			)
			(layer "F.Fab")
		)
		(fp_line
			(start -0.12065 0.2794)
			(end -0.12065 0.3048)
			(stroke
				(width 0.1)
				(type default)
			)
			(layer "F.Fab")
		)
		(fp_line
			(start -0.12065 0.3048)
			(end -0.67945 0.3048)
			(stroke
				(width 0.1)
				(type default)
			)
			(layer "F.Fab")
		)
		(fp_line
			(start 0.120396 0.2794)
			(end -0.12065 0.2794)
			(stroke
				(width 0.1)
				(type default)
			)
			(layer "F.Fab")
		)
		(fp_line
			(start 0.120396 0.3048)
			(end 0.120396 0.2794)
			(stroke
				(width 0.1)
				(type default)
			)
			(layer "F.Fab")
		)
		(fp_line
			(start 0.12065 -0.3048)
			(end 0.67945 -0.3048)
			(stroke
				(width 0.1)
				(type default)
			)
			(layer "F.Fab")
		)
		(fp_line
			(start 0.12065 -0.2794)
			(end 0.12065 -0.3048)
			(stroke
				(width 0.1)
				(type default)
			)
			(layer "F.Fab")
		)
		(fp_line
			(start 0.67945 -0.3048)
			(end 0.67945 0.3048)
			(stroke
				(width 0.1)
				(type default)
			)
			(layer "F.Fab")
		)
		(fp_line
			(start 0.67945 0.3048)
			(end 0.120396 0.3048)
			(stroke
				(width 0.1)
				(type default)
			)
			(layer "F.Fab")
		)
		(pad "1" smd circle
			(at -0.40005 0)
			(size 0 0)
			(layers "F.Cu" "F.Mask" "F.Paste")
			(net "PVDD11_S3_P1")
		)
		(pad "2" smd circle
			(at 0.40005 0)
			(size 0 0)
			(layers "F.Cu" "F.Mask" "F.Paste")
			(net "GND")
		)
	)
	(footprint ""
		(layer "F.Cu")
		(at 322.147946 -416.899344 -90)
		(property "Reference" "C6514"
			(at 0 0 270)
			(layer "F.SilkS")
			(hide yes)
			(effects
				(font
					(size 1.27 1.27)
				)
			)
		)
		(property "Value" ""
			(at 0 0 270)
			(layer "F.Fab")
			(effects
				(font
					(size 1.27 1.27)
				)
			)
		)
		(duplicate_pad_numbers_are_jumpers no)
		(fp_line
			(start -0.299974 0.150114)
			(end -0.299974 -0.150114)
			(stroke
				(width 0.1)
				(type default)
			)
			(layer "F.Fab")
		)
		(fp_line
			(start 0.299974 0.150114)
			(end -0.299974 0.150114)
			(stroke
				(width 0.1)
				(type default)
			)
			(layer "F.Fab")
		)
		(fp_line
			(start -0.299974 -0.150114)
			(end 0.299974 -0.150114)
			(stroke
				(width 0.1)
				(type default)
			)
			(layer "F.Fab")
		)
		(fp_line
			(start 0.299974 -0.150114)
			(end 0.299974 0.150114)
			(stroke
				(width 0.1)
				(type default)
			)
			(layer "F.Fab")
		)
		(pad "1" smd rect
			(at -0.2667 0 270)
			(size 0.3048 0.381)
			(layers "F.Cu" "F.Mask" "F.Paste")
			(net "P5E_CPU0_P0_TX_BUF_C_DN<6>")
		)
		(pad "2" smd rect
			(at 0.2667 0 270)
			(size 0.3048 0.381)
			(layers "F.Cu" "F.Mask" "F.Paste")
			(net "P5E_CPU0_P0_TX_BUF_DN<6>")
		)
	)
)
